# S9S_MB_2U (Grand Teton) — schematic netlist excerpt (pin names and nets, part order shuffled) for the footprints in the layout excerpt that follows; sources: Cadence DE-HDL packaged netlist, KiCad conversion of 03242023_DA0F0TMBIJ0_F0T_Motherboard_J_brd_V01_OCP.brd

C344  Q_CAP  47UF 4V 20% X6S  pkg C0805  page 79 : A = PVCCIN_CPU1 ; B = GND
D47  SCHOTTKY_12  B0530WS7F IC  pkg SOD323XB  page 115 : A = PWRGD_FAIL_CPU1_CD_R1 ; C = P3V3_AUX

(kicad_pcb
	(version 20260206)
	(generator "pcbnew")
	(generator_version "10.0")
	(general
		(thickness 1.6)
		(legacy_teardrops no)
	)
	(paper "A4")
	(title_block
		(title "03242023_DA0F0TMBIJ0_F0T_Motherboard_J_brd_V01_OCP.brd")
		(comment 1 "Grand Teton / footprints 5336-5337 of 6105")
	)
	(layers
		(0 "F.Cu" signal "TOP")
		(4 "In1.Cu" signal "GND")
		(6 "In2.Cu" signal "IN1")
		(8 "In3.Cu" signal "GND1")
		(10 "In4.Cu" signal "IN2")
		(12 "In5.Cu" signal "GND2")
		(14 "In6.Cu" signal "IN3")
		(16 "In7.Cu" signal "GND3")
		(18 "In8.Cu" signal "VCC")
		(20 "In9.Cu" signal "VCC1")
		(22 "In10.Cu" signal "GND4")
		(24 "In11.Cu" signal "IN4")
		(26 "In12.Cu" signal "GND5")
		(28 "In13.Cu" signal "IN5")
		(30 "In14.Cu" signal "GND6")
		(32 "In15.Cu" signal "IN6")
		(34 "In16.Cu" signal "GND7")
		(2 "B.Cu" signal "BOTTOM")
		(9 "F.Adhes" user "F.Adhesive")
		(11 "B.Adhes" user "B.Adhesive")
		(13 "F.Paste" user "Package Geometry/Pastemask Top")
		(15 "B.Paste" user "Package Geometry/Pastemask Bottom")
		(5 "F.SilkS" user "Ref Des/Silkscreen Top")
		(7 "B.SilkS" user "Ref Des/Silkscreen Bottom")
		(1 "F.Mask" user "Board Geometry/Soldermask Top")
		(3 "B.Mask" user "Board Geometry/Soldermask Bottom")
		(17 "Dwgs.User" user "User.Drawings")
		(19 "Cmts.User" user "User.Comments")
		(21 "Eco1.User" user "User.Eco1")
		(23 "Eco2.User" user "User.Eco2")
		(25 "Edge.Cuts" user "Board Geometry/Outline")
		(27 "Margin" user)
		(31 "F.CrtYd" user "Package Geometry/Place Bound Top")
		(29 "B.CrtYd" user "Package Geometry/Place Bound Bottom")
		(35 "F.Fab" user "Ref Des/Assembly Top")
		(33 "B.Fab" user "Ref Des/Assembly Bottom")
	)
	(footprint ""
		(layer "B.Cu")
		(at 38.335458 -315.46673 -90)
		(property "Reference" "D47"
			(at 3.662172 3.237738 0)
			(unlocked yes)
			(layer "B.SilkS")
			(effects
				(font
					(size 0.7874 0.5842)
					(thickness 0.1524)
				)
				(justify left mirror)
			)
		)
		(property "Value" ""
			(at 0 0 90)
			(layer "B.Fab")
			(effects
				(font
					(size 1.27 1.27)
				)
				(justify mirror)
			)
		)
		(duplicate_pad_numbers_are_jumpers no)
		(fp_line
			(start -2.050796 0.700024)
			(end 2.050796 0.700024)
			(stroke
				(width 0.1524)
				(type default)
			)
			(layer "B.SilkS")
		)
		(fp_line
			(start 2.050796 0.700024)
			(end 2.050796 -0.700024)
			(stroke
				(width 0.1524)
				(type default)
			)
			(layer "B.SilkS")
		)
		(fp_line
			(start -2.343404 0.6985)
			(end -2.216404 0.6985)
			(stroke
				(width 0.1524)
				(type default)
			)
			(layer "B.SilkS")
		)
		(fp_line
			(start -2.229104 0.6985)
			(end -2.051304 0.6985)
			(stroke
				(width 0.1524)
				(type default)
			)
			(layer "B.SilkS")
		)
		(fp_line
			(start -2.051304 0.6985)
			(end -2.051304 0.635)
			(stroke
				(width 0.1524)
				(type default)
			)
			(layer "B.SilkS")
		)
		(fp_line
			(start -2.152904 0.635)
			(end -2.152904 -0.6985)
			(stroke
				(width 0.1524)
				(type default)
			)
			(layer "B.SilkS")
		)
		(fp_line
			(start -2.051304 0.635)
			(end -2.152904 0.635)
			(stroke
				(width 0.1524)
				(type default)
			)
			(layer "B.SilkS")
		)
		(fp_line
			(start 0.30607 0.500126)
			(end -0.193802 0)
			(stroke
				(width 0.1524)
				(type default)
			)
			(layer "B.SilkS")
		)
		(fp_line
			(start -0.193802 0)
			(end 0.30607 -0.500126)
			(stroke
				(width 0.1524)
				(type default)
			)
			(layer "B.SilkS")
		)
		(fp_line
			(start -0.293878 -0.500126)
			(end -0.293878 0.500126)
			(stroke
				(width 0.1524)
				(type default)
			)
			(layer "B.SilkS")
		)
		(fp_line
			(start 0.30607 -0.500126)
			(end 0.30607 0.500126)
			(stroke
				(width 0.1524)
				(type default)
			)
			(layer "B.SilkS")
		)
		(fp_line
			(start -2.064004 -0.6731)
			(end -2.064004 -0.6985)
			(stroke
				(width 0.1524)
				(type default)
			)
			(layer "B.SilkS")
		)
		(fp_line
			(start -2.343404 -0.6985)
			(end -2.343404 0.6985)
			(stroke
				(width 0.1524)
				(type default)
			)
			(layer "B.SilkS")
		)
		(fp_line
			(start -2.229104 -0.6985)
			(end -2.229104 0.6985)
			(stroke
				(width 0.1524)
				(type default)
			)
			(layer "B.SilkS")
		)
		(fp_line
			(start -2.152904 -0.6985)
			(end -2.343404 -0.6985)
			(stroke
				(width 0.1524)
				(type default)
			)
			(layer "B.SilkS")
		)
		(fp_line
			(start -2.064004 -0.6985)
			(end -2.229104 -0.6985)
			(stroke
				(width 0.1524)
				(type default)
			)
			(layer "B.SilkS")
		)
		(fp_line
			(start -2.050796 -0.700024)
			(end -2.050796 0.700024)
			(stroke
				(width 0.1524)
				(type default)
			)
			(layer "B.SilkS")
		)
		(fp_line
			(start 2.050796 -0.700024)
			(end -2.050796 -0.700024)
			(stroke
				(width 0.1524)
				(type default)
			)
			(layer "B.SilkS")
		)
		(fp_line
			(start -0.899922 0.700024)
			(end 0.899922 0.700024)
			(stroke
				(width 0.1)
				(type default)
			)
			(layer "B.Fab")
		)
		(fp_line
			(start 0.899922 0.700024)
			(end 0.899922 -0.700024)
			(stroke
				(width 0.1)
				(type default)
			)
			(layer "B.Fab")
		)
		(fp_line
			(start -0.899922 -0.700024)
			(end -0.899922 0.700024)
			(stroke
				(width 0.1)
				(type default)
			)
			(layer "B.Fab")
		)
		(fp_line
			(start 0.899922 -0.700024)
			(end -0.899922 -0.700024)
			(stroke
				(width 0.1)
				(type default)
			)
			(layer "B.Fab")
		)
		(fp_text user "-"
			(at -0.138938 1.966468 90)
			(unlocked yes)
			(layer "B.SilkS")
			(effects
				(font
					(size 1.905 1.4224)
					(thickness 0.1524)
				)
				(justify left mirror)
			)
		)
		(fp_text user "+"
			(at 3.123946 0.762 180)
			(unlocked yes)
			(layer "B.SilkS")
			(effects
				(font
					(size 1.905 1.4224)
					(thickness 0.1524)
				)
				(justify left mirror)
			)
		)
		(fp_text user "+"
			(at 3.123946 0.762 180)
			(unlocked yes)
			(layer "B.Fab")
			(effects
				(font
					(size 1.905 1.4224)
					(thickness 0.1524)
				)
				(justify left mirror)
			)
		)
		(fp_text user "-"
			(at -3.880104 0.23495 90)
			(unlocked yes)
			(layer "B.Fab")
			(effects
				(font
					(size 1.905 1.4224)
					(thickness 0.1524)
				)
				(justify left mirror)
			)
		)
		(pad "1" smd rect
			(at 1.199896 0 180)
			(size 0.6604 1.3716)
			(layers "B.Cu" "B.Mask" "B.Paste")
			(net "PWRGD_FAIL_CPU1_CD_R1")
		)
		(pad "2" smd rect
			(at -1.199896 0)
			(size 0.6604 1.3716)
			(layers "B.Cu" "B.Mask" "B.Paste")
			(net "P3V3_AUX")
		)
	)
	(footprint ""
		(layer "B.Cu")
		(at 105.670604 -296.05478)
		(property "Reference" "C344"
			(at 0 0 0)
			(layer "B.SilkS")
			(hide yes)
			(effects
				(font
					(size 1.27 1.27)
				)
				(justify mirror)
			)
		)
		(property "Value" ""
			(at 0 0 0)
			(layer "B.Fab")
			(effects
				(font
					(size 1.27 1.27)
				)
				(justify mirror)
			)
		)
		(duplicate_pad_numbers_are_jumpers no)
		(fp_line
			(start -1.524 -0.762)
			(end -1.524 0.762)
			(stroke
				(width 0.1524)
				(type default)
			)
			(layer "B.SilkS")
		)
		(fp_line
			(start -1.524 0.762)
			(end 1.524 0.762)
			(stroke
				(width 0.1524)
				(type default)
			)
			(layer "B.SilkS")
		)
		(fp_line
			(start 1.524 -0.762)
			(end -1.524 -0.762)
			(stroke
				(width 0.1524)
				(type default)
			)
			(layer "B.SilkS")
		)
		(fp_line
			(start 1.524 0.762)
			(end 1.524 -0.762)
			(stroke
				(width 0.1524)
				(type default)
			)
			(layer "B.SilkS")
		)
		(fp_line
			(start -1.1049 -0.724916)
			(end 1.1049 -0.724916)
			(stroke
				(width 0.1)
				(type default)
			)
			(layer "B.Fab")
		)
		(fp_line
			(start -1.1049 0.724916)
			(end -1.1049 -0.724916)
			(stroke
				(width 0.1)
				(type default)
			)
			(layer "B.Fab")
		)
		(fp_line
			(start 1.1049 -0.724916)
			(end 1.1049 0.724916)
			(stroke
				(width 0.1)
				(type default)
			)
			(layer "B.Fab")
		)
		(fp_line
			(start 1.1049 0.724916)
			(end -1.1049 0.724916)
			(stroke
				(width 0.1)
				(type default)
			)
			(layer "B.Fab")
		)
		(pad "1" smd rect
			(at 0.889 0)
			(size 1.016 1.27)
			(layers "B.Cu" "B.Mask" "B.Paste")
			(net "PVCCIN_CPU1")
		)
		(pad "2" smd rect
			(at -0.889 0)
			(size 1.016 1.27)
			(layers "B.Cu" "B.Mask" "B.Paste")
			(net "GND")
		)
	)
)
